# T6G (Grand Teton) — schematic netlist excerpt (pin names and nets, part order shuffled) for the footprints in the layout excerpt that follows; sources: Cadence DE-HDL packaged netlist, KiCad conversion of 04192023_DAF0TMB3IC0_F0TG_MB_C_brd_V02_OCP.brd

R1180  Q_RES  0 5% EMPTY  pkg 0402LF  page 247 : A = HP_LVC3_OCP_V3_2_R_EN ; B = HP_LVC3_OCP_V3_2_P12V_PWRGD
R243  Q_RES  0 5% CHIP  pkg 0402LF  page 82 : A = FM_SMM_CRASHDUMP ; B = FM_SMM_CRASHDUMP_R

(kicad_pcb
	(version 20260206)
	(generator "pcbnew")
	(generator_version "10.0")
	(general
		(thickness 1.6)
		(legacy_teardrops no)
	)
	(paper "A4")
	(title_block
		(title "04192023_DAF0TMB3IC0_F0TG_MB_C_brd_V02_OCP.brd")
		(comment 1 "Grand Teton / footprints 2200-2201 of 8354")
	)
	(layers
		(0 "F.Cu" signal "TOP")
		(4 "In1.Cu" signal "GND")
		(6 "In2.Cu" signal "IN1")
		(8 "In3.Cu" signal "GND1")
		(10 "In4.Cu" signal "IN2")
		(12 "In5.Cu" signal "GND2")
		(14 "In6.Cu" signal "IN3")
		(16 "In7.Cu" signal "GND3")
		(18 "In8.Cu" signal "VCC")
		(20 "In9.Cu" signal "VCC1")
		(22 "In10.Cu" signal "GND4")
		(24 "In11.Cu" signal "IN4")
		(26 "In12.Cu" signal "GND5")
		(28 "In13.Cu" signal "IN5")
		(30 "In14.Cu" signal "GND6")
		(32 "In15.Cu" signal "IN6")
		(34 "In16.Cu" signal "GND7")
		(2 "B.Cu" signal "BOTTOM")
		(9 "F.Adhes" user "F.Adhesive")
		(11 "B.Adhes" user "B.Adhesive")
		(13 "F.Paste" user "Package Geometry/Pastemask Top")
		(15 "B.Paste" user "Package Geometry/Pastemask Bottom")
		(5 "F.SilkS" user "Ref Des/Silkscreen Top")
		(7 "B.SilkS" user "Ref Des/Silkscreen Bottom")
		(1 "F.Mask" user "Board Geometry/Soldermask Top")
		(3 "B.Mask" user "Board Geometry/Soldermask Bottom")
		(17 "Dwgs.User" user "User.Drawings")
		(19 "Cmts.User" user "User.Comments")
		(21 "Eco1.User" user "User.Eco1")
		(23 "Eco2.User" user "User.Eco2")
		(25 "Edge.Cuts" user "Board Geometry/Outline")
		(27 "Margin" user)
		(31 "F.CrtYd" user "Package Geometry/Place Bound Top")
		(29 "B.CrtYd" user "Package Geometry/Place Bound Bottom")
		(35 "F.Fab" user "Ref Des/Assembly Top")
		(33 "B.Fab" user "Ref Des/Assembly Bottom")
	)
	(footprint ""
		(layer "F.Cu")
		(at 178.689 -100.294948 90)
		(property "Reference" "R243"
			(at 0 0 90)
			(layer "F.SilkS")
			(hide yes)
			(effects
				(font
					(size 1.27 1.27)
				)
			)
		)
		(property "Value" ""
			(at 0 0 90)
			(layer "F.Fab")
			(effects
				(font
					(size 1.27 1.27)
				)
			)
		)
		(duplicate_pad_numbers_are_jumpers no)
		(fp_line
			(start 0.7874 -0.4064)
			(end 0.7874 0.4064)
			(stroke
				(width 0.1524)
				(type default)
			)
			(layer "F.SilkS")
		)
		(fp_line
			(start -0.7874 -0.4064)
			(end 0.7874 -0.4064)
			(stroke
				(width 0.1524)
				(type default)
			)
			(layer "F.SilkS")
		)
		(fp_line
			(start 0.7874 0.4064)
			(end -0.7874 0.4064)
			(stroke
				(width 0.1524)
				(type default)
			)
			(layer "F.SilkS")
		)
		(fp_line
			(start -0.7874 0.4064)
			(end -0.7874 -0.4064)
			(stroke
				(width 0.1524)
				(type default)
			)
			(layer "F.SilkS")
		)
		(fp_line
			(start -0.12065 -0.305054)
			(end -0.12065 -0.2794)
			(stroke
				(width 0.1)
				(type default)
			)
			(layer "F.Fab")
		)
		(fp_line
			(start -0.67945 -0.305054)
			(end -0.12065 -0.305054)
			(stroke
				(width 0.1)
				(type default)
			)
			(layer "F.Fab")
		)
		(fp_line
			(start 0.67945 -0.3048)
			(end 0.67945 0.3048)
			(stroke
				(width 0.1)
				(type default)
			)
			(layer "F.Fab")
		)
		(fp_line
			(start 0.12065 -0.3048)
			(end 0.67945 -0.3048)
			(stroke
				(width 0.1)
				(type default)
			)
			(layer "F.Fab")
		)
		(fp_line
			(start 0.12065 -0.2794)
			(end 0.12065 -0.3048)
			(stroke
				(width 0.1)
				(type default)
			)
			(layer "F.Fab")
		)
		(fp_line
			(start -0.12065 -0.2794)
			(end 0.12065 -0.2794)
			(stroke
				(width 0.1)
				(type default)
			)
			(layer "F.Fab")
		)
		(fp_line
			(start 0.120396 0.2794)
			(end -0.12065 0.2794)
			(stroke
				(width 0.1)
				(type default)
			)
			(layer "F.Fab")
		)
		(fp_line
			(start -0.12065 0.2794)
			(end -0.12065 0.3048)
			(stroke
				(width 0.1)
				(type default)
			)
			(layer "F.Fab")
		)
		(fp_line
			(start 0.67945 0.3048)
			(end 0.120396 0.3048)
			(stroke
				(width 0.1)
				(type default)
			)
			(layer "F.Fab")
		)
		(fp_line
			(start 0.120396 0.3048)
			(end 0.120396 0.2794)
			(stroke
				(width 0.1)
				(type default)
			)
			(layer "F.Fab")
		)
		(fp_line
			(start -0.12065 0.3048)
			(end -0.67945 0.3048)
			(stroke
				(width 0.1)
				(type default)
			)
			(layer "F.Fab")
		)
		(fp_line
			(start -0.67945 0.3048)
			(end -0.67945 -0.305054)
			(stroke
				(width 0.1)
				(type default)
			)
			(layer "F.Fab")
		)
		(pad "1" smd circle
			(at -0.40005 0 90)
			(size 0 0)
			(layers "F.Cu" "F.Mask" "F.Paste")
			(net "FM_SMM_CRASHDUMP")
		)
		(pad "2" smd circle
			(at 0.40005 0 90)
			(size 0 0)
			(layers "F.Cu" "F.Mask" "F.Paste")
			(net "FM_SMM_CRASHDUMP_R")
		)
	)
	(footprint ""
		(layer "F.Cu")
		(at 152.848818 -34.647632)
		(property "Reference" "R1180"
			(at 0 0 0)
			(layer "F.SilkS")
			(hide yes)
			(effects
				(font
					(size 1.27 1.27)
				)
			)
		)
		(property "Value" ""
			(at 0 0 0)
			(layer "F.Fab")
			(effects
				(font
					(size 1.27 1.27)
				)
			)
		)
		(duplicate_pad_numbers_are_jumpers no)
		(fp_line
			(start -0.7874 -0.4064)
			(end 0.7874 -0.4064)
			(stroke
				(width 0.1524)
				(type default)
			)
			(layer "F.SilkS")
		)
		(fp_line
			(start -0.7874 0.4064)
			(end -0.7874 -0.4064)
			(stroke
				(width 0.1524)
				(type default)
			)
			(layer "F.SilkS")
		)
		(fp_line
			(start 0.7874 -0.4064)
			(end 0.7874 0.4064)
			(stroke
				(width 0.1524)
				(type default)
			)
			(layer "F.SilkS")
		)
		(fp_line
			(start 0.7874 0.4064)
			(end -0.7874 0.4064)
			(stroke
				(width 0.1524)
				(type default)
			)
			(layer "F.SilkS")
		)
		(fp_line
			(start -0.67945 -0.305054)
			(end -0.12065 -0.305054)
			(stroke
				(width 0.1)
				(type default)
			)
			(layer "F.Fab")
		)
		(fp_line
			(start -0.67945 0.3048)
			(end -0.67945 -0.305054)
			(stroke
				(width 0.1)
				(type default)
			)
			(layer "F.Fab")
		)
		(fp_line
			(start -0.12065 -0.305054)
			(end -0.12065 -0.2794)
			(stroke
				(width 0.1)
				(type default)
			)
			(layer "F.Fab")
		)
		(fp_line
			(start -0.12065 -0.2794)
			(end 0.12065 -0.2794)
			(stroke
				(width 0.1)
				(type default)
			)
			(layer "F.Fab")
		)
		(fp_line
			(start -0.12065 0.2794)
			(end -0.12065 0.3048)
			(stroke
				(width 0.1)
				(type default)
			)
			(layer "F.Fab")
		)
		(fp_line
			(start -0.12065 0.3048)
			(end -0.67945 0.3048)
			(stroke
				(width 0.1)
				(type default)
			)
			(layer "F.Fab")
		)
		(fp_line
			(start 0.120396 0.2794)
			(end -0.12065 0.2794)
			(stroke
				(width 0.1)
				(type default)
			)
			(layer "F.Fab")
		)
		(fp_line
			(start 0.120396 0.3048)
			(end 0.120396 0.2794)
			(stroke
				(width 0.1)
				(type default)
			)
			(layer "F.Fab")
		)
		(fp_line
			(start 0.12065 -0.3048)
			(end 0.67945 -0.3048)
			(stroke
				(width 0.1)
				(type default)
			)
			(layer "F.Fab")
		)
		(fp_line
			(start 0.12065 -0.2794)
			(end 0.12065 -0.3048)
			(stroke
				(width 0.1)
				(type default)
			)
			(layer "F.Fab")
		)
		(fp_line
			(start 0.67945 -0.3048)
			(end 0.67945 0.3048)
			(stroke
				(width 0.1)
				(type default)
			)
			(layer "F.Fab")
		)
		(fp_line
			(start 0.67945 0.3048)
			(end 0.120396 0.3048)
			(stroke
				(width 0.1)
				(type default)
			)
			(layer "F.Fab")
		)
		(pad "1" smd circle
			(at -0.40005 0)
			(size 0 0)
			(layers "F.Cu" "F.Mask" "F.Paste")
			(net "HP_LVC3_OCP_V3_2_R_EN")
		)
		(pad "2" smd circle
			(at 0.40005 0)
			(size 0 0)
			(layers "F.Cu" "F.Mask" "F.Paste")
			(net "HP_LVC3_OCP_V3_2_P12V_PWRGD")
		)
	)
)
